(kicad_pcb
	(version 20260206)
	(generator "pcbnew")
	(generator_version "10.0")
	(general
		(thickness 1.6)
		(legacy_teardrops no)
	)
	(paper "A4")
	(title_block
		(title "01162023_DA0F0TEBIF0_F0T_Expander_BD_F_brd_V02_OCP.brd")
		(comment 1 "Grand Teton / footprints 8742-8750 of 9728")
	)
	(layers
		(0 "F.Cu" signal "TOP")
		(4 "In1.Cu" signal "GND")
		(6 "In2.Cu" signal "VCC")
		(8 "In3.Cu" signal "VCC1")
		(10 "In4.Cu" signal "GND1")
		(12 "In5.Cu" signal "IN1")
		(14 "In6.Cu" signal "GND2")
		(16 "In7.Cu" signal "IN2")
		(18 "In8.Cu" signal "GND3")
		(20 "In9.Cu" signal "IN3")
		(22 "In10.Cu" signal "GND4")
		(24 "In11.Cu" signal "IN4")
		(26 "In12.Cu" signal "GND5")
		(28 "In13.Cu" signal "IN5")
		(30 "In14.Cu" signal "GND6")
		(32 "In15.Cu" signal "IN6")
		(34 "In16.Cu" signal "GND7")
		(2 "B.Cu" signal "BOTTOM")
		(9 "F.Adhes" user "F.Adhesive")
		(11 "B.Adhes" user "B.Adhesive")
		(13 "F.Paste" user "Package Geometry/Pastemask Top")
		(15 "B.Paste" user "Package Geometry/Pastemask Bottom")
		(5 "F.SilkS" user "Ref Des/Silkscreen Top")
		(7 "B.SilkS" user "Ref Des/Silkscreen Bottom")
		(1 "F.Mask" user "Board Geometry/Soldermask Top")
		(3 "B.Mask" user "Board Geometry/Soldermask Bottom")
		(17 "Dwgs.User" user "User.Drawings")
		(19 "Cmts.User" user "User.Comments")
		(21 "Eco1.User" user "User.Eco1")
		(23 "Eco2.User" user "User.Eco2")
		(25 "Edge.Cuts" user "Board Geometry/Outline")
		(27 "Margin" user)
		(31 "F.CrtYd" user "Package Geometry/Place Bound Top")
		(29 "B.CrtYd" user "Package Geometry/Place Bound Bottom")
		(35 "F.Fab" user "Ref Des/Assembly Top")
		(33 "B.Fab" user "Ref Des/Assembly Bottom")
	)
	(footprint ""
		(layer "B.Cu")
		(at 54.424834 -286.399732 90)
		(property "Reference" "C2972"
			(at 0 0 90)
			(layer "B.SilkS")
			(hide yes)
			(effects
				(font
					(size 1.27 1.27)
				)
				(justify mirror)
			)
		)
		(property "Value" ""
			(at 0 0 90)
			(layer "B.Fab")
			(effects
				(font
					(size 1.27 1.27)
				)
				(justify mirror)
			)
		)
		(duplicate_pad_numbers_are_jumpers no)
		(fp_line
			(start 0.299974 -0.150114)
			(end -0.299974 -0.150114)
			(stroke
				(width 0.1)
				(type default)
			)
			(layer "B.Fab")
		)
		(fp_line
			(start -0.299974 -0.150114)
			(end -0.299974 0.150114)
			(stroke
				(width 0.1)
				(type default)
			)
			(layer "B.Fab")
		)
		(fp_line
			(start 0.299974 0.150114)
			(end 0.299974 -0.150114)
			(stroke
				(width 0.1)
				(type default)
			)
			(layer "B.Fab")
		)
		(fp_line
			(start -0.299974 0.150114)
			(end 0.299974 0.150114)
			(stroke
				(width 0.1)
				(type default)
			)
			(layer "B.Fab")
		)
		(pad "1" smd rect
			(at 0.2667 0 270)
			(size 0.3048 0.381)
			(layers "B.Cu" "B.Mask" "B.Paste")
			(net "P1V25_SERDES_VDDPLL_PEX0")
		)
		(pad "2" smd rect
			(at -0.2667 0 270)
			(size 0.3048 0.381)
			(layers "B.Cu" "B.Mask" "B.Paste")
			(net "GND")
		)
	)
	(footprint ""
		(layer "B.Cu")
		(at 66.774822 -286.399732 90)
		(property "Reference" "C2963"
			(at 0 0 90)
			(layer "B.SilkS")
			(hide yes)
			(effects
				(font
					(size 1.27 1.27)
				)
				(justify mirror)
			)
		)
		(property "Value" ""
			(at 0 0 90)
			(layer "B.Fab")
			(effects
				(font
					(size 1.27 1.27)
				)
				(justify mirror)
			)
		)
		(duplicate_pad_numbers_are_jumpers no)
		(fp_line
			(start 0.299974 -0.150114)
			(end -0.299974 -0.150114)
			(stroke
				(width 0.1)
				(type default)
			)
			(layer "B.Fab")
		)
		(fp_line
			(start -0.299974 -0.150114)
			(end -0.299974 0.150114)
			(stroke
				(width 0.1)
				(type default)
			)
			(layer "B.Fab")
		)
		(fp_line
			(start 0.299974 0.150114)
			(end 0.299974 -0.150114)
			(stroke
				(width 0.1)
				(type default)
			)
			(layer "B.Fab")
		)
		(fp_line
			(start -0.299974 0.150114)
			(end 0.299974 0.150114)
			(stroke
				(width 0.1)
				(type default)
			)
			(layer "B.Fab")
		)
		(pad "1" smd rect
			(at 0.2667 0 270)
			(size 0.3048 0.381)
			(layers "B.Cu" "B.Mask" "B.Paste")
			(net "P1V25_SERDES_VDDPLL_PEX0")
		)
		(pad "2" smd rect
			(at -0.2667 0 270)
			(size 0.3048 0.381)
			(layers "B.Cu" "B.Mask" "B.Paste")
			(net "GND")
		)
	)
	(footprint ""
		(layer "B.Cu")
		(at 169.099992 -299.699934 -90)
		(property "Reference" "C1436"
			(at 0 0 90)
			(layer "B.SilkS")
			(hide yes)
			(effects
				(font
					(size 1.27 1.27)
				)
				(justify mirror)
			)
		)
		(property "Value" ""
			(at 0 0 90)
			(layer "B.Fab")
			(effects
				(font
					(size 1.27 1.27)
				)
				(justify mirror)
			)
		)
		(duplicate_pad_numbers_are_jumpers no)
		(fp_line
			(start -0.299974 0.150114)
			(end 0.299974 0.150114)
			(stroke
				(width 0.1)
				(type default)
			)
			(layer "B.Fab")
		)
		(fp_line
			(start 0.299974 0.150114)
			(end 0.299974 -0.150114)
			(stroke
				(width 0.1)
				(type default)
			)
			(layer "B.Fab")
		)
		(fp_line
			(start -0.299974 -0.150114)
			(end -0.299974 0.150114)
			(stroke
				(width 0.1)
				(type default)
			)
			(layer "B.Fab")
		)
		(fp_line
			(start 0.299974 -0.150114)
			(end -0.299974 -0.150114)
			(stroke
				(width 0.1)
				(type default)
			)
			(layer "B.Fab")
		)
		(pad "1" smd rect
			(at 0.2667 0 90)
			(size 0.3048 0.381)
			(layers "B.Cu" "B.Mask" "B.Paste")
			(net "P0V8_SERDES_VDDA_PEX1")
		)
		(pad "2" smd rect
			(at -0.2667 0 90)
			(size 0.3048 0.381)
			(layers "B.Cu" "B.Mask" "B.Paste")
			(net "GND")
		)
	)
	(footprint ""
		(layer "B.Cu")
		(at 279.974802 -292.84168 90)
		(property "Reference" "C3394"
			(at 0 0 90)
			(layer "B.SilkS")
			(hide yes)
			(effects
				(font
					(size 1.27 1.27)
				)
				(justify mirror)
			)
		)
		(property "Value" ""
			(at 0 0 90)
			(layer "B.Fab")
			(effects
				(font
					(size 1.27 1.27)
				)
				(justify mirror)
			)
		)
		(duplicate_pad_numbers_are_jumpers no)
		(fp_line
			(start 0.299974 -0.150114)
			(end -0.299974 -0.150114)
			(stroke
				(width 0.1)
				(type default)
			)
			(layer "B.Fab")
		)
		(fp_line
			(start -0.299974 -0.150114)
			(end -0.299974 0.150114)
			(stroke
				(width 0.1)
				(type default)
			)
			(layer "B.Fab")
		)
		(fp_line
			(start 0.299974 0.150114)
			(end 0.299974 -0.150114)
			(stroke
				(width 0.1)
				(type default)
			)
			(layer "B.Fab")
		)
		(fp_line
			(start -0.299974 0.150114)
			(end 0.299974 0.150114)
			(stroke
				(width 0.1)
				(type default)
			)
			(layer "B.Fab")
		)
		(pad "1" smd rect
			(at 0.2667 0 270)
			(size 0.3048 0.381)
			(layers "B.Cu" "B.Mask" "B.Paste")
			(net "PCEPLL5_VDDA18_PEX2")
		)
		(pad "2" smd rect
			(at -0.2667 0 270)
			(size 0.3048 0.381)
			(layers "B.Cu" "B.Mask" "B.Paste")
			(net "GND")
		)
	)
	(footprint ""
		(layer "B.Cu")
		(at 156.750004 -288.774886 -90)
		(property "Reference" "R3451"
			(at 0 0 90)
			(layer "B.SilkS")
			(hide yes)
			(effects
				(font
					(size 1.27 1.27)
				)
				(justify mirror)
			)
		)
		(property "Value" ""
			(at 0 0 90)
			(layer "B.Fab")
			(effects
				(font
					(size 1.27 1.27)
				)
				(justify mirror)
			)
		)
		(duplicate_pad_numbers_are_jumpers no)
		(fp_line
			(start -0.7874 0.4064)
			(end 0.7874 0.4064)
			(stroke
				(width 0.1524)
				(type default)
			)
			(layer "B.SilkS")
		)
		(fp_line
			(start 0.7874 0.4064)
			(end 0.7874 -0.4064)
			(stroke
				(width 0.1524)
				(type default)
			)
			(layer "B.SilkS")
		)
		(fp_line
			(start -0.7874 -0.4064)
			(end -0.7874 0.4064)
			(stroke
				(width 0.1524)
				(type default)
			)
			(layer "B.SilkS")
		)
		(fp_line
			(start 0.7874 -0.4064)
			(end -0.7874 -0.4064)
			(stroke
				(width 0.1524)
				(type default)
			)
			(layer "B.SilkS")
		)
		(fp_line
			(start -0.67945 0.3048)
			(end -0.120396 0.3048)
			(stroke
				(width 0.1)
				(type default)
			)
			(layer "B.Fab")
		)
		(fp_line
			(start -0.120396 0.3048)
			(end -0.120396 0.2794)
			(stroke
				(width 0.1)
				(type default)
			)
			(layer "B.Fab")
		)
		(fp_line
			(start 0.12065 0.3048)
			(end 0.67945 0.3048)
			(stroke
				(width 0.1)
				(type default)
			)
			(layer "B.Fab")
		)
		(fp_line
			(start 0.67945 0.3048)
			(end 0.67945 -0.305054)
			(stroke
				(width 0.1)
				(type default)
			)
			(layer "B.Fab")
		)
		(fp_line
			(start -0.120396 0.2794)
			(end 0.12065 0.2794)
			(stroke
				(width 0.1)
				(type default)
			)
			(layer "B.Fab")
		)
		(fp_line
			(start 0.12065 0.2794)
			(end 0.12065 0.3048)
			(stroke
				(width 0.1)
				(type default)
			)
			(layer "B.Fab")
		)
		(fp_line
			(start -0.12065 -0.2794)
			(end -0.12065 -0.3048)
			(stroke
				(width 0.1)
				(type default)
			)
			(layer "B.Fab")
		)
		(fp_line
			(start 0.12065 -0.2794)
			(end -0.12065 -0.2794)
			(stroke
				(width 0.1)
				(type default)
			)
			(layer "B.Fab")
		)
		(fp_line
			(start -0.67945 -0.3048)
			(end -0.67945 0.3048)
			(stroke
				(width 0.1)
				(type default)
			)
			(layer "B.Fab")
		)
		(fp_line
			(start -0.12065 -0.3048)
			(end -0.67945 -0.3048)
			(stroke
				(width 0.1)
				(type default)
			)
			(layer "B.Fab")
		)
		(fp_line
			(start 0.12065 -0.305054)
			(end 0.12065 -0.2794)
			(stroke
				(width 0.1)
				(type default)
			)
			(layer "B.Fab")
		)
		(fp_line
			(start 0.67945 -0.305054)
			(end 0.12065 -0.305054)
			(stroke
				(width 0.1)
				(type default)
			)
			(layer "B.Fab")
		)
		(pad "1" smd circle
			(at 0.40005 0 90)
			(size 0 0)
			(layers "B.Cu" "B.Mask" "B.Paste")
			(net "SPI_PEX1_CS_R_N")
		)
		(pad "2" smd circle
			(at -0.40005 0 90)
			(size 0 0)
			(layers "B.Cu" "B.Mask" "B.Paste")
			(net "SPI_PEX1_CS_N")
		)
	)
	(footprint ""
		(layer "B.Cu")
		(at 221.257114 -210.201002)
		(property "Reference" "C2011"
			(at 0 0 0)
			(layer "B.SilkS")
			(hide yes)
			(effects
				(font
					(size 1.27 1.27)
				)
				(justify mirror)
			)
		)
		(property "Value" ""
			(at 0 0 0)
			(layer "B.Fab")
			(effects
				(font
					(size 1.27 1.27)
				)
				(justify mirror)
			)
		)
		(duplicate_pad_numbers_are_jumpers no)
		(fp_line
			(start -1.2954 -0.5842)
			(end -1.2954 0.5842)
			(stroke
				(width 0.1524)
				(type default)
			)
			(layer "B.SilkS")
		)
		(fp_line
			(start -1.2954 0.5842)
			(end 1.2954 0.5842)
			(stroke
				(width 0.1524)
				(type default)
			)
			(layer "B.SilkS")
		)
		(fp_line
			(start 1.2954 -0.5842)
			(end -1.2954 -0.5842)
			(stroke
				(width 0.1524)
				(type default)
			)
			(layer "B.SilkS")
		)
		(fp_line
			(start 1.2954 0.5842)
			(end 1.2954 -0.5842)
			(stroke
				(width 0.1524)
				(type default)
			)
			(layer "B.SilkS")
		)
		(fp_line
			(start -1.1938 -0.4064)
			(end -1.1938 0.4064)
			(stroke
				(width 0.1)
				(type default)
			)
			(layer "B.Fab")
		)
		(fp_line
			(start -1.1938 0.4064)
			(end -0.8636 0.4064)
			(stroke
				(width 0.1)
				(type default)
			)
			(layer "B.Fab")
		)
		(fp_line
			(start -0.8636 -0.4572)
			(end -0.8636 -0.4064)
			(stroke
				(width 0.1)
				(type default)
			)
			(layer "B.Fab")
		)
		(fp_line
			(start -0.8636 -0.4064)
			(end -1.1938 -0.4064)
			(stroke
				(width 0.1)
				(type default)
			)
			(layer "B.Fab")
		)
		(fp_line
			(start -0.8636 0.4064)
			(end -0.8636 0.4572)
			(stroke
				(width 0.1)
				(type default)
			)
			(layer "B.Fab")
		)
		(fp_line
			(start -0.8636 0.4572)
			(end 0.8636 0.4572)
			(stroke
				(width 0.1)
				(type default)
			)
			(layer "B.Fab")
		)
		(fp_line
			(start 0.8636 -0.4572)
			(end -0.8636 -0.4572)
			(stroke
				(width 0.1)
				(type default)
			)
			(layer "B.Fab")
		)
		(fp_line
			(start 0.8636 -0.4064)
			(end 0.8636 -0.4572)
			(stroke
				(width 0.1)
				(type default)
			)
			(layer "B.Fab")
		)
		(fp_line
			(start 0.8636 0.4064)
			(end 1.1938 0.4064)
			(stroke
				(width 0.1)
				(type default)
			)
			(layer "B.Fab")
		)
		(fp_line
			(start 0.8636 0.4572)
			(end 0.8636 0.4064)
			(stroke
				(width 0.1)
				(type default)
			)
			(layer "B.Fab")
		)
		(fp_line
			(start 1.1938 -0.4064)
			(end 0.8636 -0.4064)
			(stroke
				(width 0.1)
				(type default)
			)
			(layer "B.Fab")
		)
		(fp_line
			(start 1.1938 0.4064)
			(end 1.1938 -0.4064)
			(stroke
				(width 0.1)
				(type default)
			)
			(layer "B.Fab")
		)
		(pad "1" smd rect
			(at 0.7366 0 270)
			(size 0.7112 0.8128)
			(layers "B.Cu" "B.Mask" "B.Paste")
			(net "P3V3_AUX")
		)
		(pad "2" smd rect
			(at -0.7366 0 270)
			(size 0.7112 0.8128)
			(layers "B.Cu" "B.Mask" "B.Paste")
			(net "GND")
		)
	)
	(footprint ""
		(layer "B.Cu")
		(at 253.97968 -86.856316 180)
		(property "Reference" "R1048"
			(at 0 0 0)
			(layer "B.SilkS")
			(hide yes)
			(effects
				(font
					(size 1.27 1.27)
				)
				(justify mirror)
			)
		)
		(property "Value" ""
			(at 0 0 0)
			(layer "B.Fab")
			(effects
				(font
					(size 1.27 1.27)
				)
				(justify mirror)
			)
		)
		(duplicate_pad_numbers_are_jumpers no)
		(fp_line
			(start 1.2954 0.5842)
			(end 1.2954 -0.5842)
			(stroke
				(width 0.1524)
				(type default)
			)
			(layer "B.SilkS")
		)
		(fp_line
			(start 1.2954 -0.5842)
			(end -1.2954 -0.5842)
			(stroke
				(width 0.1524)
				(type default)
			)
			(layer "B.SilkS")
		)
		(fp_line
			(start -1.2954 0.5842)
			(end 1.2954 0.5842)
			(stroke
				(width 0.1524)
				(type default)
			)
			(layer "B.SilkS")
		)
		(fp_line
			(start -1.2954 -0.5842)
			(end -1.2954 0.5842)
			(stroke
				(width 0.1524)
				(type default)
			)
			(layer "B.SilkS")
		)
		(fp_line
			(start 1.1938 0.4064)
			(end 1.1938 -0.406654)
			(stroke
				(width 0.1)
				(type default)
			)
			(layer "B.Fab")
		)
		(fp_line
			(start 1.1938 -0.406654)
			(end 0.8636 -0.406654)
			(stroke
				(width 0.1)
				(type default)
			)
			(layer "B.Fab")
		)
		(fp_line
			(start 0.8636 0.4572)
			(end 0.8636 0.4318)
			(stroke
				(width 0.1)
				(type default)
			)
			(layer "B.Fab")
		)
		(fp_line
			(start 0.8636 0.4318)
			(end 0.8636 0.4064)
			(stroke
				(width 0.1)
				(type default)
			)
			(layer "B.Fab")
		)
		(fp_line
			(start 0.8636 0.4064)
			(end 1.1938 0.4064)
			(stroke
				(width 0.1)
				(type default)
			)
			(layer "B.Fab")
		)
		(fp_line
			(start 0.8636 -0.406654)
			(end 0.8636 -0.4572)
			(stroke
				(width 0.1)
				(type default)
			)
			(layer "B.Fab")
		)
		(fp_line
			(start 0.8636 -0.4572)
			(end -0.8636 -0.4572)
			(stroke
				(width 0.1)
				(type default)
			)
			(layer "B.Fab")
		)
		(fp_line
			(start -0.8636 0.4572)
			(end 0.8636 0.4572)
			(stroke
				(width 0.1)
				(type default)
			)
			(layer "B.Fab")
		)
		(fp_line
			(start -0.8636 0.4064)
			(end -0.8636 0.4572)
			(stroke
				(width 0.1)
				(type default)
			)
			(layer "B.Fab")
		)
		(fp_line
			(start -0.8636 -0.406654)
			(end -1.1938 -0.406654)
			(stroke
				(width 0.1)
				(type default)
			)
			(layer "B.Fab")
		)
		(fp_line
			(start -0.8636 -0.4572)
			(end -0.8636 -0.406654)
			(stroke
				(width 0.1)
				(type default)
			)
			(layer "B.Fab")
		)
		(fp_line
			(start -1.1938 0.4064)
			(end -0.8636 0.4064)
			(stroke
				(width 0.1)
				(type default)
			)
			(layer "B.Fab")
		)
		(fp_line
			(start -1.1938 -0.406654)
			(end -1.1938 0.4064)
			(stroke
				(width 0.1)
				(type default)
			)
			(layer "B.Fab")
		)
		(pad "1" smd rect
			(at 0.7366 0 90)
			(size 0.7112 0.8128)
			(layers "B.Cu" "B.Mask" "B.Paste")
			(net "P3V3_CLK_GEN_VDDMXCK_CK440")
		)
		(pad "2" smd rect
			(at -0.7366 0 90)
			(size 0.7112 0.8128)
			(layers "B.Cu" "B.Mask" "B.Paste")
			(net "P3V3_CLK_GEN_VDDPT_CK440")
		)
	)
	(footprint ""
		(layer "B.Cu")
		(at 12.964922 -391.185146 -90)
		(property "Reference" "L151"
			(at -0.766064 1.406906 0)
			(unlocked yes)
			(layer "B.SilkS")
			(effects
				(font
					(size 0.7874 0.5842)
					(thickness 0.1524)
				)
				(justify left mirror)
			)
		)
		(property "Value" ""
			(at 0 0 90)
			(layer "B.Fab")
			(effects
				(font
					(size 1.27 1.27)
				)
				(justify mirror)
			)
		)
		(duplicate_pad_numbers_are_jumpers no)
		(fp_line
			(start -1.63576 0.8128)
			(end 1.63576 0.8128)
			(stroke
				(width 0.1524)
				(type default)
			)
			(layer "B.SilkS")
		)
		(fp_line
			(start -1.63576 -0.8128)
			(end -1.63576 0.8128)
			(stroke
				(width 0.1524)
				(type default)
			)
			(layer "B.SilkS")
		)
		(fp_line
			(start 1.63576 -0.8128)
			(end 1.63576 0.8128)
			(stroke
				(width 0.1524)
				(type default)
			)
			(layer "B.SilkS")
		)
		(fp_line
			(start 1.63576 -0.8128)
			(end -1.63576 -0.8128)
			(stroke
				(width 0.1524)
				(type default)
			)
			(layer "B.SilkS")
		)
		(fp_line
			(start -1.560576 0.7366)
			(end -1.560576 -0.738632)
			(stroke
				(width 0.1)
				(type default)
			)
			(layer "B.Fab")
		)
		(fp_line
			(start -1.524 0.7366)
			(end -1.560576 0.7366)
			(stroke
				(width 0.1)
				(type default)
			)
			(layer "B.Fab")
		)
		(fp_line
			(start 1.524 0.7366)
			(end -1.524 0.7366)
			(stroke
				(width 0.1)
				(type default)
			)
			(layer "B.Fab")
		)
		(fp_line
			(start 1.56083 0.7366)
			(end 1.524 0.7366)
			(stroke
				(width 0.1)
				(type default)
			)
			(layer "B.Fab")
		)
		(fp_line
			(start -1.560576 -0.738632)
			(end 1.56083 -0.738632)
			(stroke
				(width 0.1)
				(type default)
			)
			(layer "B.Fab")
		)
		(fp_line
			(start 1.56083 -0.738632)
			(end 1.56083 0.7366)
			(stroke
				(width 0.1)
				(type default)
			)
			(layer "B.Fab")
		)
		(pad "1" smd rect
			(at 0.94996 0 270)
			(size 1.1176 1.3716)
			(layers "B.Cu" "B.Mask" "B.Paste")
			(net "P1V2_USB_8042")
		)
		(pad "2" smd rect
			(at -0.94996 0 270)
			(size 1.1176 1.3716)
			(layers "B.Cu" "B.Mask" "B.Paste")
			(net "P1V2_AUX")
		)
	)
	(footprint ""
		(layer "B.Cu")
		(at 102.02926 -277.639272)
		(property "Reference" "PC6607"
			(at 0 0 0)
			(layer "B.SilkS")
			(hide yes)
			(effects
				(font
					(size 1.27 1.27)
				)
				(justify mirror)
			)
		)
		(property "Value" ""
			(at 0 0 0)
			(layer "B.Fab")
			(effects
				(font
					(size 1.27 1.27)
				)
				(justify mirror)
			)
		)
		(duplicate_pad_numbers_are_jumpers no)
		(fp_line
			(start -1.524 -0.762)
			(end -1.524 0.762)
			(stroke
				(width 0.1524)
				(type default)
			)
			(layer "B.SilkS")
		)
		(fp_line
			(start -1.524 0.762)
			(end 1.524 0.762)
			(stroke
				(width 0.1524)
				(type default)
			)
			(layer "B.SilkS")
		)
		(fp_line
			(start 1.524 -0.762)
			(end -1.524 -0.762)
			(stroke
				(width 0.1524)
				(type default)
			)
			(layer "B.SilkS")
		)
		(fp_line
			(start 1.524 0.762)
			(end 1.524 -0.762)
			(stroke
				(width 0.1524)
				(type default)
			)
			(layer "B.SilkS")
		)
		(fp_line
			(start -1.1049 -0.724916)
			(end 1.1049 -0.724916)
			(stroke
				(width 0.1)
				(type default)
			)
			(layer "B.Fab")
		)
		(fp_line
			(start -1.1049 0.724916)
			(end -1.1049 -0.724916)
			(stroke
				(width 0.1)
				(type default)
			)
			(layer "B.Fab")
		)
		(fp_line
			(start 1.1049 -0.724916)
			(end 1.1049 0.724916)
			(stroke
				(width 0.1)
				(type default)
			)
			(layer "B.Fab")
		)
		(fp_line
			(start 1.1049 0.724916)
			(end -1.1049 0.724916)
			(stroke
				(width 0.1)
				(type default)
			)
			(layer "B.Fab")
		)
		(pad "1" smd rect
			(at 0.889 0)
			(size 1.016 1.27)
			(layers "B.Cu" "B.Mask" "B.Paste")
			(net "SW_P12V_P0V8_PEX0_FLT")
		)
		(pad "2" smd rect
			(at -0.889 0)
			(size 1.016 1.27)
			(layers "B.Cu" "B.Mask" "B.Paste")
			(net "GND")
		)
	)
)
